# SCM (Grand Teton) — schematic netlist excerpt (pin names and nets, part order shuffled) for the footprints in the layout excerpt that follows; sources: Cadence DE-HDL packaged netlist, KiCad conversion of 12092022_DA0F0TMDCD0_F0T_Management_Board_D_brd_V3_OCP.brd

R681  Q_RES  33.2 1% EMPTY  pkg 0402LF  page 13 : A = SPI_BMC_IO2_R ; B = QSPI_2_PLD_IO2
R654  Q_RES  33.2 1% EMPTY  pkg 0402LF  page 21 : A = EMMC_CLK_R ; B = BMC_EMMC_CLK

(kicad_pcb
	(version 20260206)
	(generator "pcbnew")
	(generator_version "10.0")
	(general
		(thickness 1.6)
		(legacy_teardrops no)
	)
	(paper "A4")
	(title_block
		(title "12092022_DA0F0TMDCD0_F0T_Management_Board_D_brd_V3_OCP.brd")
		(comment 1 "Grand Teton / footprints 316-317 of 1440")
	)
	(layers
		(0 "F.Cu" signal "TOP")
		(4 "In1.Cu" signal "GND")
		(6 "In2.Cu" signal "IN1")
		(8 "In3.Cu" signal "GND1")
		(10 "In4.Cu" signal "IN2")
		(12 "In5.Cu" signal "VCC")
		(14 "In6.Cu" signal "VCC1")
		(16 "In7.Cu" signal "IN3")
		(18 "In8.Cu" signal "GND2")
		(20 "In9.Cu" signal "IN4")
		(22 "In10.Cu" signal "GND3")
		(2 "B.Cu" signal "BOTTOM")
		(9 "F.Adhes" user "F.Adhesive")
		(11 "B.Adhes" user "B.Adhesive")
		(13 "F.Paste" user "Package Geometry/Pastemask Top")
		(15 "B.Paste" user "Package Geometry/Pastemask Bottom")
		(5 "F.SilkS" user "Ref Des/Silkscreen Top")
		(7 "B.SilkS" user "Ref Des/Silkscreen Bottom")
		(1 "F.Mask" user "Board Geometry/Soldermask Top")
		(3 "B.Mask" user "Board Geometry/Soldermask Bottom")
		(17 "Dwgs.User" user "User.Drawings")
		(19 "Cmts.User" user "User.Comments")
		(21 "Eco1.User" user "User.Eco1")
		(23 "Eco2.User" user "User.Eco2")
		(25 "Edge.Cuts" user "Board Geometry/Outline")
		(27 "Margin" user)
		(31 "F.CrtYd" user "Package Geometry/Place Bound Top")
		(29 "B.CrtYd" user "Package Geometry/Place Bound Bottom")
		(35 "F.Fab" user "Ref Des/Assembly Top")
		(33 "B.Fab" user "Ref Des/Assembly Bottom")
	)
	(footprint ""
		(layer "F.Cu")
		(at 28.935172 -83.816952 90)
		(property "Reference" "R654"
			(at 0 0 90)
			(layer "F.SilkS")
			(hide yes)
			(effects
				(font
					(size 1.27 1.27)
				)
			)
		)
		(property "Value" ""
			(at 0 0 90)
			(layer "F.Fab")
			(effects
				(font
					(size 1.27 1.27)
				)
			)
		)
		(duplicate_pad_numbers_are_jumpers no)
		(fp_line
			(start 0.7874 -0.4064)
			(end 0.7874 0.4064)
			(stroke
				(width 0.1524)
				(type default)
			)
			(layer "F.SilkS")
		)
		(fp_line
			(start -0.7874 -0.4064)
			(end 0.7874 -0.4064)
			(stroke
				(width 0.1524)
				(type default)
			)
			(layer "F.SilkS")
		)
		(fp_line
			(start 0.7874 0.4064)
			(end -0.7874 0.4064)
			(stroke
				(width 0.1524)
				(type default)
			)
			(layer "F.SilkS")
		)
		(fp_line
			(start -0.7874 0.4064)
			(end -0.7874 -0.4064)
			(stroke
				(width 0.1524)
				(type default)
			)
			(layer "F.SilkS")
		)
		(fp_line
			(start -0.12065 -0.305054)
			(end -0.12065 -0.2794)
			(stroke
				(width 0.1)
				(type default)
			)
			(layer "F.Fab")
		)
		(fp_line
			(start -0.67945 -0.305054)
			(end -0.12065 -0.305054)
			(stroke
				(width 0.1)
				(type default)
			)
			(layer "F.Fab")
		)
		(fp_line
			(start 0.67945 -0.3048)
			(end 0.67945 0.3048)
			(stroke
				(width 0.1)
				(type default)
			)
			(layer "F.Fab")
		)
		(fp_line
			(start 0.12065 -0.3048)
			(end 0.67945 -0.3048)
			(stroke
				(width 0.1)
				(type default)
			)
			(layer "F.Fab")
		)
		(fp_line
			(start 0.12065 -0.2794)
			(end 0.12065 -0.3048)
			(stroke
				(width 0.1)
				(type default)
			)
			(layer "F.Fab")
		)
		(fp_line
			(start -0.12065 -0.2794)
			(end 0.12065 -0.2794)
			(stroke
				(width 0.1)
				(type default)
			)
			(layer "F.Fab")
		)
		(fp_line
			(start 0.120396 0.2794)
			(end -0.12065 0.2794)
			(stroke
				(width 0.1)
				(type default)
			)
			(layer "F.Fab")
		)
		(fp_line
			(start -0.12065 0.2794)
			(end -0.12065 0.3048)
			(stroke
				(width 0.1)
				(type default)
			)
			(layer "F.Fab")
		)
		(fp_line
			(start 0.67945 0.3048)
			(end 0.120396 0.3048)
			(stroke
				(width 0.1)
				(type default)
			)
			(layer "F.Fab")
		)
		(fp_line
			(start 0.120396 0.3048)
			(end 0.120396 0.2794)
			(stroke
				(width 0.1)
				(type default)
			)
			(layer "F.Fab")
		)
		(fp_line
			(start -0.12065 0.3048)
			(end -0.67945 0.3048)
			(stroke
				(width 0.1)
				(type default)
			)
			(layer "F.Fab")
		)
		(fp_line
			(start -0.67945 0.3048)
			(end -0.67945 -0.305054)
			(stroke
				(width 0.1)
				(type default)
			)
			(layer "F.Fab")
		)
		(pad "1" smd circle
			(at -0.40005 0 90)
			(size 0 0)
			(layers "F.Cu" "F.Mask" "F.Paste")
			(net "EMMC_CLK_R")
		)
		(pad "2" smd circle
			(at 0.40005 0 90)
			(size 0 0)
			(layers "F.Cu" "F.Mask" "F.Paste")
			(net "BMC_EMMC_CLK")
		)
	)
	(footprint ""
		(layer "F.Cu")
		(at 55.4228 -63.6524 90)
		(property "Reference" "R681"
			(at 0 0 90)
			(layer "F.SilkS")
			(hide yes)
			(effects
				(font
					(size 1.27 1.27)
				)
			)
		)
		(property "Value" ""
			(at 0 0 90)
			(layer "F.Fab")
			(effects
				(font
					(size 1.27 1.27)
				)
			)
		)
		(duplicate_pad_numbers_are_jumpers no)
		(fp_line
			(start 0.7874 -0.4064)
			(end 0.7874 0.4064)
			(stroke
				(width 0.1524)
				(type default)
			)
			(layer "F.SilkS")
		)
		(fp_line
			(start -0.7874 -0.4064)
			(end 0.7874 -0.4064)
			(stroke
				(width 0.1524)
				(type default)
			)
			(layer "F.SilkS")
		)
		(fp_line
			(start 0.7874 0.4064)
			(end -0.7874 0.4064)
			(stroke
				(width 0.1524)
				(type default)
			)
			(layer "F.SilkS")
		)
		(fp_line
			(start -0.7874 0.4064)
			(end -0.7874 -0.4064)
			(stroke
				(width 0.1524)
				(type default)
			)
			(layer "F.SilkS")
		)
		(fp_line
			(start -0.12065 -0.305054)
			(end -0.12065 -0.2794)
			(stroke
				(width 0.1)
				(type default)
			)
			(layer "F.Fab")
		)
		(fp_line
			(start -0.67945 -0.305054)
			(end -0.12065 -0.305054)
			(stroke
				(width 0.1)
				(type default)
			)
			(layer "F.Fab")
		)
		(fp_line
			(start 0.67945 -0.3048)
			(end 0.67945 0.3048)
			(stroke
				(width 0.1)
				(type default)
			)
			(layer "F.Fab")
		)
		(fp_line
			(start 0.12065 -0.3048)
			(end 0.67945 -0.3048)
			(stroke
				(width 0.1)
				(type default)
			)
			(layer "F.Fab")
		)
		(fp_line
			(start 0.12065 -0.2794)
			(end 0.12065 -0.3048)
			(stroke
				(width 0.1)
				(type default)
			)
			(layer "F.Fab")
		)
		(fp_line
			(start -0.12065 -0.2794)
			(end 0.12065 -0.2794)
			(stroke
				(width 0.1)
				(type default)
			)
			(layer "F.Fab")
		)
		(fp_line
			(start 0.120396 0.2794)
			(end -0.12065 0.2794)
			(stroke
				(width 0.1)
				(type default)
			)
			(layer "F.Fab")
		)
		(fp_line
			(start -0.12065 0.2794)
			(end -0.12065 0.3048)
			(stroke
				(width 0.1)
				(type default)
			)
			(layer "F.Fab")
		)
		(fp_line
			(start 0.67945 0.3048)
			(end 0.120396 0.3048)
			(stroke
				(width 0.1)
				(type default)
			)
			(layer "F.Fab")
		)
		(fp_line
			(start 0.120396 0.3048)
			(end 0.120396 0.2794)
			(stroke
				(width 0.1)
				(type default)
			)
			(layer "F.Fab")
		)
		(fp_line
			(start -0.12065 0.3048)
			(end -0.67945 0.3048)
			(stroke
				(width 0.1)
				(type default)
			)
			(layer "F.Fab")
		)
		(fp_line
			(start -0.67945 0.3048)
			(end -0.67945 -0.305054)
			(stroke
				(width 0.1)
				(type default)
			)
			(layer "F.Fab")
		)
		(pad "1" smd circle
			(at -0.40005 0 90)
			(size 0 0)
			(layers "F.Cu" "F.Mask" "F.Paste")
			(net "SPI_BMC_IO2_R")
		)
		(pad "2" smd circle
			(at 0.40005 0 90)
			(size 0 0)
			(layers "F.Cu" "F.Mask" "F.Paste")
			(net "QSPI_2_PLD_IO2")
		)
	)
)
